(kicad_pcb
	(version 20260206)
	(generator "pcbnew")
	(generator_version "10.0")
	(general
		(thickness 1.6)
		(legacy_teardrops no)
	)
	(paper "A4")
	(title_block
		(title "timecard-production-celestica-r4006 — R4006-B0001-02_R01.brd")
		(comment 1 "Time Appliance Project (Time Card) / footprints 469-473 of 1113")
	)
	(layers
		(0 "F.Cu" signal "TOP")
		(4 "In1.Cu" signal "L02_GND1")
		(6 "In2.Cu" signal "L03_SIG1")
		(8 "In3.Cu" signal "L04_GND2")
		(10 "In4.Cu" signal "L05_VCC1")
		(12 "In5.Cu" signal "L06_VCC2")
		(14 "In6.Cu" signal "L07_GND3")
		(16 "In7.Cu" signal "L08_SIG2")
		(18 "In8.Cu" signal "L09_GND4")
		(2 "B.Cu" signal "BOTTOM")
		(9 "F.Adhes" user "F.Adhesive")
		(11 "B.Adhes" user "B.Adhesive")
		(13 "F.Paste" user "Package Geometry/Pastemask Top")
		(15 "B.Paste" user "Package Geometry/Pastemask Bottom")
		(5 "F.SilkS" user "Ref Des/Silkscreen Top")
		(7 "B.SilkS" user "Ref Des/Silkscreen Bottom")
		(1 "F.Mask" user "Board Geometry/Soldermask Top")
		(3 "B.Mask" user "Board Geometry/Soldermask Bottom")
		(17 "Dwgs.User" user "User.Drawings")
		(19 "Cmts.User" user "User.Comments")
		(21 "Eco1.User" user "User.Eco1")
		(23 "Eco2.User" user "User.Eco2")
		(25 "Edge.Cuts" user "Board Geometry/Outline")
		(27 "Margin" user)
		(31 "F.CrtYd" user "Package Geometry/Place Bound Top")
		(29 "B.CrtYd" user "Package Geometry/Place Bound Bottom")
		(35 "F.Fab" user "Ref Des/Assembly Top")
		(33 "B.Fab" user "Ref Des/Assembly Bottom")
	)
	(footprint ""
		(layer "F.Cu")
		(at 119.761 -21.971)
		(property "Reference" "R474"
			(at -2.794 0.92837 0)
			(unlocked yes)
			(layer "F.SilkS")
			(effects
				(font
					(size 0.7874 0.5842)
					(thickness 0.1524)
				)
			)
		)
		(property "Value" "VAL*"
			(at 0.02032 2.13233 0)
			(unlocked yes)
			(layer "F.Fab")
			(hide yes)
			(effects
				(font
					(size 0.7874 0.5842)
					(thickness 0.1524)
				)
			)
		)
		(property "Tolerance" "TOL*"
			(at 0.044704 3.05435 0)
			(unlocked yes)
			(layer "Cmts.User")
			(hide yes)
			(effects
				(font
					(size 0.7874 0.5842)
					(thickness 0.1524)
				)
			)
		)
		(property "User Part Number" "PARTNUM*"
			(at 0.02032 4.024884 0)
			(unlocked yes)
			(layer "Cmts.User")
			(hide yes)
			(effects
				(font
					(size 0.7874 0.5842)
					(thickness 0.1524)
				)
			)
		)
		(property "Device Type" "RESISTOR-G155-11003-01,100KOHMA"
			(at 0.008382 1.210564 0)
			(unlocked yes)
			(layer "F.Fab")
			(hide yes)
			(effects
				(font
					(size 0.7874 0.5842)
					(thickness 0.1524)
				)
			)
		)
		(duplicate_pad_numbers_are_jumpers no)
		(fp_line
			(start -1.143 -0.5588)
			(end -1.143 0.5588)
			(stroke
				(width 0.1)
				(type default)
			)
			(layer "F.SilkS")
		)
		(fp_line
			(start -1.143 0.5588)
			(end 1.143 0.5588)
			(stroke
				(width 0.1)
				(type default)
			)
			(layer "F.SilkS")
		)
		(fp_line
			(start 1.143 -0.5588)
			(end -1.143 -0.5588)
			(stroke
				(width 0.1)
				(type default)
			)
			(layer "F.SilkS")
		)
		(fp_line
			(start 1.143 0.5588)
			(end 1.143 -0.5588)
			(stroke
				(width 0.1)
				(type default)
			)
			(layer "F.SilkS")
		)
		(fp_poly
			(pts
				(xy -1.143 0.5588) (xy 1.143 0.5588) (xy 1.143 -0.5588) (xy -1.143 -0.5588)
			)
			(stroke
				(width 0)
				(type default)
			)
			(fill no)
			(layer "F.CrtYd")
		)
		(fp_line
			(start -0.508 -0.3048)
			(end -0.508 0.3048)
			(stroke
				(width 0.1)
				(type default)
			)
			(layer "F.Fab")
		)
		(fp_line
			(start -0.508 0.3048)
			(end 0.508 0.3048)
			(stroke
				(width 0.1)
				(type default)
			)
			(layer "F.Fab")
		)
		(fp_line
			(start 0.508 -0.3048)
			(end -0.508 -0.3048)
			(stroke
				(width 0.1)
				(type default)
			)
			(layer "F.Fab")
		)
		(fp_line
			(start 0.508 0.3048)
			(end 0.508 -0.3048)
			(stroke
				(width 0.1)
				(type default)
			)
			(layer "F.Fab")
		)
		(pad "1" smd rect
			(at -0.5334 0)
			(size 0.7112 0.6096)
			(layers "F.Cu" "F.Mask" "F.Paste")
			(net "XP3R3V_FPGA")
		)
		(pad "2" smd rect
			(at 0.5334 0)
			(size 0.7112 0.6096)
			(layers "F.Cu" "F.Mask" "F.Paste")
			(net "FPGA_PCA9546_I2C_SDA")
		)
		(zone
			(layer "F.Cu")
			(hatch none 0.5)
			(connect_pads
				(clearance 0)
			)
			(min_thickness 0.25)
			(keepout
				(tracks allowed)
				(vias not_allowed)
				(pads allowed)
				(copperpour not_allowed)
				(footprints allowed)
			)
			(placement
				(enabled no)
				(sheetname "")
			)
			(fill
				(thermal_gap 0.5)
				(thermal_bridge_width 0.5)
				(island_removal_mode 0)
			)
			(polygon
				(pts
					(xy 119.6848 -21.6662) (xy 119.8372 -21.6662) (xy 119.8372 -22.2758) (xy 119.6848 -22.2758)
				)
			)
		)
		(zone
			(layer "F.Cu")
			(hatch none 0.5)
			(connect_pads
				(clearance 0)
			)
			(min_thickness 0.25)
			(keepout
				(tracks not_allowed)
				(vias allowed)
				(pads allowed)
				(copperpour not_allowed)
				(footprints allowed)
			)
			(placement
				(enabled no)
				(sheetname "")
			)
			(fill
				(thermal_gap 0.5)
				(thermal_bridge_width 0.5)
				(island_removal_mode 0)
			)
			(polygon
				(pts
					(xy 119.6848 -21.6662) (xy 119.8372 -21.6662) (xy 119.8372 -22.2758) (xy 119.6848 -22.2758)
				)
			)
		)
	)
	(footprint ""
		(layer "F.Cu")
		(at 36.703 -94.615 -90)
		(property "Reference" "C74"
			(at 3.72237 -2.032 0)
			(unlocked yes)
			(layer "F.SilkS")
			(effects
				(font
					(size 0.7874 0.5842)
					(thickness 0.1524)
				)
			)
		)
		(property "Value" "VAL*"
			(at 0.0762 2.067306 270)
			(unlocked yes)
			(layer "F.Fab")
			(hide yes)
			(effects
				(font
					(size 0.7874 0.5842)
					(thickness 0.1524)
				)
			)
		)
		(property "Device Type" "CAPACITOR-G105-0B104-EK,0.1UF,A"
			(at 0.0508 1.127506 270)
			(unlocked yes)
			(layer "F.Fab")
			(hide yes)
			(effects
				(font
					(size 0.7874 0.5842)
					(thickness 0.1524)
				)
			)
		)
		(property "User Part Number" "PARTNUM*"
			(at 0.1016 4.023106 270)
			(unlocked yes)
			(layer "Cmts.User")
			(hide yes)
			(effects
				(font
					(size 0.7874 0.5842)
					(thickness 0.1524)
				)
			)
		)
		(property "Tolerance" "TOL*"
			(at 0.0762 3.032506 270)
			(unlocked yes)
			(layer "Cmts.User")
			(hide yes)
			(effects
				(font
					(size 0.7874 0.5842)
					(thickness 0.1524)
				)
			)
		)
		(duplicate_pad_numbers_are_jumpers no)
		(fp_line
			(start -1.143 0.5588)
			(end 1.143 0.5588)
			(stroke
				(width 0.1)
				(type default)
			)
			(layer "F.SilkS")
		)
		(fp_line
			(start 1.143 0.5588)
			(end 1.143 -0.5588)
			(stroke
				(width 0.1)
				(type default)
			)
			(layer "F.SilkS")
		)
		(fp_line
			(start -1.143 -0.5588)
			(end -1.143 0.5588)
			(stroke
				(width 0.1)
				(type default)
			)
			(layer "F.SilkS")
		)
		(fp_line
			(start 1.143 -0.5588)
			(end -1.143 -0.5588)
			(stroke
				(width 0.1)
				(type default)
			)
			(layer "F.SilkS")
		)
		(fp_rect
			(start -1.143 0.5588)
			(end 1.143 -0.5588)
			(stroke
				(width 0)
				(type default)
			)
			(fill no)
			(layer "F.CrtYd")
		)
		(fp_line
			(start -0.508 0.3048)
			(end 0.508 0.3048)
			(stroke
				(width 0.1)
				(type default)
			)
			(layer "F.Fab")
		)
		(fp_line
			(start 0.508 0.3048)
			(end 0.508 -0.3048)
			(stroke
				(width 0.1)
				(type default)
			)
			(layer "F.Fab")
		)
		(fp_line
			(start -0.508 -0.3048)
			(end -0.508 0.3048)
			(stroke
				(width 0.1)
				(type default)
			)
			(layer "F.Fab")
		)
		(fp_line
			(start 0.508 -0.3048)
			(end -0.508 -0.3048)
			(stroke
				(width 0.1)
				(type default)
			)
			(layer "F.Fab")
		)
		(pad "1" smd rect
			(at -0.5334 0 270)
			(size 0.7112 0.6096)
			(layers "F.Cu" "F.Mask" "F.Paste")
			(net "XP12R0V")
		)
		(pad "2" smd rect
			(at 0.5334 0 270)
			(size 0.7112 0.6096)
			(layers "F.Cu" "F.Mask" "F.Paste")
			(net "SG")
		)
		(zone
			(layer "F.Cu")
			(hatch none 0.5)
			(connect_pads
				(clearance 0)
			)
			(min_thickness 0.25)
			(keepout
				(tracks allowed)
				(vias not_allowed)
				(pads allowed)
				(copperpour not_allowed)
				(footprints allowed)
			)
			(placement
				(enabled no)
				(sheetname "")
			)
			(fill
				(thermal_gap 0.5)
				(thermal_bridge_width 0.5)
				(island_removal_mode 0)
			)
			(polygon
				(pts
					(xy 36.3982 -94.6912) (xy 36.3982 -94.5388) (xy 37.0078 -94.5388) (xy 37.0078 -94.6912)
				)
			)
		)
	)
	(footprint ""
		(layer "F.Cu")
		(at 112.1156 -26.7208 90)
		(property "Reference" "C251"
			(at -8.4328 -0.31623 90)
			(unlocked yes)
			(layer "F.SilkS")
			(effects
				(font
					(size 0.7874 0.5842)
					(thickness 0.1524)
				)
			)
		)
		(property "Value" "VAL*"
			(at 0.0762 2.067306 90)
			(unlocked yes)
			(layer "F.Fab")
			(hide yes)
			(effects
				(font
					(size 0.7874 0.5842)
					(thickness 0.1524)
				)
			)
		)
		(property "Device Type" "CAPACITOR-G105-0B104-CK,0.1UF,A"
			(at 0.0508 1.127506 90)
			(unlocked yes)
			(layer "F.Fab")
			(hide yes)
			(effects
				(font
					(size 0.7874 0.5842)
					(thickness 0.1524)
				)
			)
		)
		(property "User Part Number" "PARTNUM*"
			(at 0.1016 4.023106 90)
			(unlocked yes)
			(layer "Cmts.User")
			(hide yes)
			(effects
				(font
					(size 0.7874 0.5842)
					(thickness 0.1524)
				)
			)
		)
		(property "Tolerance" "TOL*"
			(at 0.0762 3.032506 90)
			(unlocked yes)
			(layer "Cmts.User")
			(hide yes)
			(effects
				(font
					(size 0.7874 0.5842)
					(thickness 0.1524)
				)
			)
		)
		(duplicate_pad_numbers_are_jumpers no)
		(fp_line
			(start 1.143 -0.5588)
			(end -1.143 -0.5588)
			(stroke
				(width 0.1)
				(type default)
			)
			(layer "F.SilkS")
		)
		(fp_line
			(start -1.143 -0.5588)
			(end -1.143 0.5588)
			(stroke
				(width 0.1)
				(type default)
			)
			(layer "F.SilkS")
		)
		(fp_line
			(start 1.143 0.5588)
			(end 1.143 -0.5588)
			(stroke
				(width 0.1)
				(type default)
			)
			(layer "F.SilkS")
		)
		(fp_line
			(start -1.143 0.5588)
			(end 1.143 0.5588)
			(stroke
				(width 0.1)
				(type default)
			)
			(layer "F.SilkS")
		)
		(fp_rect
			(start 1.143 -0.5588)
			(end -1.143 0.5588)
			(stroke
				(width 0)
				(type default)
			)
			(fill no)
			(layer "F.CrtYd")
		)
		(fp_line
			(start 0.508 -0.3048)
			(end -0.508 -0.3048)
			(stroke
				(width 0.1)
				(type default)
			)
			(layer "F.Fab")
		)
		(fp_line
			(start -0.508 -0.3048)
			(end -0.508 0.3048)
			(stroke
				(width 0.1)
				(type default)
			)
			(layer "F.Fab")
		)
		(fp_line
			(start 0.508 0.3048)
			(end 0.508 -0.3048)
			(stroke
				(width 0.1)
				(type default)
			)
			(layer "F.Fab")
		)
		(fp_line
			(start -0.508 0.3048)
			(end 0.508 0.3048)
			(stroke
				(width 0.1)
				(type default)
			)
			(layer "F.Fab")
		)
		(pad "1" smd rect
			(at -0.5334 0 90)
			(size 0.7112 0.6096)
			(layers "F.Cu" "F.Mask" "F.Paste")
			(net "OSC_200M_CLKP")
		)
		(pad "2" smd rect
			(at 0.5334 0 90)
			(size 0.7112 0.6096)
			(layers "F.Cu" "F.Mask" "F.Paste")
			(net "MHZ200CLKP_CLKIN")
		)
		(zone
			(layer "F.Cu")
			(hatch none 0.5)
			(connect_pads
				(clearance 0)
			)
			(min_thickness 0.25)
			(keepout
				(tracks allowed)
				(vias not_allowed)
				(pads allowed)
				(copperpour not_allowed)
				(footprints allowed)
			)
			(placement
				(enabled no)
				(sheetname "")
			)
			(fill
				(thermal_gap 0.5)
				(thermal_bridge_width 0.5)
				(island_removal_mode 0)
			)
			(polygon
				(pts
					(xy 111.8108 -26.797) (xy 111.8108 -26.6446) (xy 112.4204 -26.6446) (xy 112.4204 -26.797)
				)
			)
		)
	)
	(footprint ""
		(layer "F.Cu")
		(at 92.372942 -59.3344 -90)
		(property "Reference" "C47"
			(at 2.29235 -0.337058 0)
			(unlocked yes)
			(layer "F.SilkS")
			(effects
				(font
					(size 0.635 0.4064)
					(thickness 0.1524)
				)
			)
		)
		(property "Value" "VAL*"
			(at 0.193548 2.13614 270)
			(unlocked yes)
			(layer "F.Fab")
			(hide yes)
			(effects
				(font
					(size 0.7874 0.5842)
					(thickness 0.1524)
				)
			)
		)
		(property "Tolerance" "TOL*"
			(at 0.216154 3.1496 270)
			(unlocked yes)
			(layer "Cmts.User")
			(hide yes)
			(effects
				(font
					(size 0.7874 0.5842)
					(thickness 0.1524)
				)
			)
		)
		(property "Device Type" "CAPACITOR-G104-0A120-FJ,12PF,5%"
			(at 0.184404 1.180592 270)
			(unlocked yes)
			(layer "F.Fab")
			(hide yes)
			(effects
				(font
					(size 0.7874 0.5842)
					(thickness 0.1524)
				)
			)
		)
		(property "User Part Number" "PARTNUM*"
			(at 0.216154 4.185666 270)
			(unlocked yes)
			(layer "Cmts.User")
			(hide yes)
			(effects
				(font
					(size 0.7874 0.5842)
					(thickness 0.1524)
				)
			)
		)
		(duplicate_pad_numbers_are_jumpers no)
		(fp_line
			(start -0.671322 0.4445)
			(end -0.671322 -0.4445)
			(stroke
				(width 0.1)
				(type default)
			)
			(layer "F.SilkS")
		)
		(fp_line
			(start 0.671322 0.4445)
			(end -0.671322 0.4445)
			(stroke
				(width 0.1)
				(type default)
			)
			(layer "F.SilkS")
		)
		(fp_line
			(start -0.671322 -0.4445)
			(end 0.671322 -0.4445)
			(stroke
				(width 0.1)
				(type default)
			)
			(layer "F.SilkS")
		)
		(fp_line
			(start 0.671322 -0.4445)
			(end 0.671322 0.4445)
			(stroke
				(width 0.1)
				(type default)
			)
			(layer "F.SilkS")
		)
		(fp_rect
			(start 0.671322 0.4445)
			(end -0.671322 -0.4445)
			(stroke
				(width 0)
				(type default)
			)
			(fill no)
			(layer "F.CrtYd")
		)
		(fp_line
			(start -0.31496 0.1651)
			(end 0.31496 0.1651)
			(stroke
				(width 0.1)
				(type default)
			)
			(layer "F.Fab")
		)
		(fp_line
			(start 0.31496 0.1651)
			(end 0.31496 -0.1651)
			(stroke
				(width 0.1)
				(type default)
			)
			(layer "F.Fab")
		)
		(fp_line
			(start -0.31496 -0.1651)
			(end -0.31496 0.1651)
			(stroke
				(width 0.1)
				(type default)
			)
			(layer "F.Fab")
		)
		(fp_line
			(start 0.31496 -0.1651)
			(end -0.31496 -0.1651)
			(stroke
				(width 0.1)
				(type default)
			)
			(layer "F.Fab")
		)
		(pad "1" smd rect
			(at -0.264922 0 270)
			(size 0.3048 0.381)
			(layers "F.Cu" "F.Mask" "F.Paste")
			(net "UNNAMED_9_BNO080LGA28_I29_XOUT3")
		)
		(pad "2" smd rect
			(at 0.264922 0 270)
			(size 0.3048 0.381)
			(layers "F.Cu" "F.Mask" "F.Paste")
			(net "SG")
		)
		(zone
			(layer "F.Cu")
			(hatch none 0.5)
			(connect_pads
				(clearance 0)
			)
			(min_thickness 0.25)
			(keepout
				(tracks allowed)
				(vias not_allowed)
				(pads allowed)
				(copperpour not_allowed)
				(footprints allowed)
			)
			(placement
				(enabled no)
				(sheetname "")
			)
			(fill
				(thermal_gap 0.5)
				(thermal_bridge_width 0.5)
				(island_removal_mode 0)
			)
			(polygon
				(pts
					(xy 92.182442 -59.221878) (xy 92.563442 -59.221878) (xy 92.563442 -59.446922) (xy 92.182442 -59.446922)
				)
			)
		)
	)
	(footprint ""
		(layer "F.Cu")
		(at 80.772 -59.5376 180)
		(property "Reference" "R301"
			(at 10.287 19.51863 0)
			(unlocked yes)
			(layer "F.SilkS")
			(effects
				(font
					(size 0.7874 0.5842)
					(thickness 0.1524)
				)
			)
		)
		(property "Value" "VAL*"
			(at 0.02032 2.13233 180)
			(unlocked yes)
			(layer "F.Fab")
			(hide yes)
			(effects
				(font
					(size 0.7874 0.5842)
					(thickness 0.1524)
				)
			)
		)
		(property "Tolerance" "TOL*"
			(at 0.044704 3.05435 180)
			(unlocked yes)
			(layer "Cmts.User")
			(hide yes)
			(effects
				(font
					(size 0.7874 0.5842)
					(thickness 0.1524)
				)
			)
		)
		(property "User Part Number" "PARTNUM*"
			(at 0.02032 4.024884 180)
			(unlocked yes)
			(layer "Cmts.User")
			(hide yes)
			(effects
				(font
					(size 0.7874 0.5842)
					(thickness 0.1524)
				)
			)
		)
		(property "Device Type" "RESISTOR-G155-14701-01,4.7KOHMA"
			(at 0.008382 1.210564 180)
			(unlocked yes)
			(layer "F.Fab")
			(hide yes)
			(effects
				(font
					(size 0.7874 0.5842)
					(thickness 0.1524)
				)
			)
		)
		(duplicate_pad_numbers_are_jumpers no)
		(fp_line
			(start 1.143 0.5588)
			(end 1.143 -0.5588)
			(stroke
				(width 0.1)
				(type default)
			)
			(layer "F.SilkS")
		)
		(fp_line
			(start 1.143 -0.5588)
			(end -1.143 -0.5588)
			(stroke
				(width 0.1)
				(type default)
			)
			(layer "F.SilkS")
		)
		(fp_line
			(start -1.143 0.5588)
			(end 1.143 0.5588)
			(stroke
				(width 0.1)
				(type default)
			)
			(layer "F.SilkS")
		)
		(fp_line
			(start -1.143 -0.5588)
			(end -1.143 0.5588)
			(stroke
				(width 0.1)
				(type default)
			)
			(layer "F.SilkS")
		)
		(fp_rect
			(start 1.143 0.5588)
			(end -1.143 -0.5588)
			(stroke
				(width 0)
				(type default)
			)
			(fill no)
			(layer "F.CrtYd")
		)
		(fp_line
			(start 0.508 0.3048)
			(end 0.508 -0.3048)
			(stroke
				(width 0.1)
				(type default)
			)
			(layer "F.Fab")
		)
		(fp_line
			(start 0.508 -0.3048)
			(end -0.508 -0.3048)
			(stroke
				(width 0.1)
				(type default)
			)
			(layer "F.Fab")
		)
		(fp_line
			(start -0.508 0.3048)
			(end 0.508 0.3048)
			(stroke
				(width 0.1)
				(type default)
			)
			(layer "F.Fab")
		)
		(fp_line
			(start -0.508 -0.3048)
			(end -0.508 0.3048)
			(stroke
				(width 0.1)
				(type default)
			)
			(layer "F.Fab")
		)
		(pad "1" smd rect
			(at -0.5334 0 180)
			(size 0.7112 0.6096)
			(layers "F.Cu" "F.Mask" "F.Paste")
			(net "R_BNO080_RST_N")
		)
		(pad "2" smd rect
			(at 0.5334 0 180)
			(size 0.7112 0.6096)
			(layers "F.Cu" "F.Mask" "F.Paste")
			(net "SG")
		)
		(zone
			(layer "F.Cu")
			(hatch none 0.5)
			(connect_pads
				(clearance 0)
			)
			(min_thickness 0.25)
			(keepout
				(tracks allowed)
				(vias not_allowed)
				(pads allowed)
				(copperpour not_allowed)
				(footprints allowed)
			)
			(placement
				(enabled no)
				(sheetname "")
			)
			(fill
				(thermal_gap 0.5)
				(thermal_bridge_width 0.5)
				(island_removal_mode 0)
			)
			(polygon
				(pts
					(xy 80.6958 -59.8424) (xy 80.6958 -59.2328) (xy 80.8482 -59.2328) (xy 80.8482 -59.8424)
				)
			)
		)
	)
)
